# S9S_MB_2U (Grand Teton) — schematic netlist excerpt (pin names and nets, part order shuffled) for the footprints in the layout excerpt that follows; sources: Cadence DE-HDL packaged netlist, KiCad conversion of 03242023_DA0F0TMBIJ0_F0T_Motherboard_J_brd_V01_OCP.brd

R3825  Q_RES  100K 1% EMPTY  pkg 0402LF  page 162 : A = P3V3_AUX ; B = HP_LVC3_OCP_V3_2_P12V_PWRGD
R2831  Q_RES  100K 1% EMPTY  pkg 0402LF  page 148 : A = BIC_MONITER ; B = GND

(kicad_pcb
	(version 20260206)
	(generator "pcbnew")
	(generator_version "10.0")
	(general
		(thickness 1.6)
		(legacy_teardrops no)
	)
	(paper "A4")
	(title_block
		(title "03242023_DA0F0TMBIJ0_F0T_Motherboard_J_brd_V01_OCP.brd")
		(comment 1 "Grand Teton / footprints 3583-3584 of 6105")
	)
	(layers
		(0 "F.Cu" signal "TOP")
		(4 "In1.Cu" signal "GND")
		(6 "In2.Cu" signal "IN1")
		(8 "In3.Cu" signal "GND1")
		(10 "In4.Cu" signal "IN2")
		(12 "In5.Cu" signal "GND2")
		(14 "In6.Cu" signal "IN3")
		(16 "In7.Cu" signal "GND3")
		(18 "In8.Cu" signal "VCC")
		(20 "In9.Cu" signal "VCC1")
		(22 "In10.Cu" signal "GND4")
		(24 "In11.Cu" signal "IN4")
		(26 "In12.Cu" signal "GND5")
		(28 "In13.Cu" signal "IN5")
		(30 "In14.Cu" signal "GND6")
		(32 "In15.Cu" signal "IN6")
		(34 "In16.Cu" signal "GND7")
		(2 "B.Cu" signal "BOTTOM")
		(9 "F.Adhes" user "F.Adhesive")
		(11 "B.Adhes" user "B.Adhesive")
		(13 "F.Paste" user "Package Geometry/Pastemask Top")
		(15 "B.Paste" user "Package Geometry/Pastemask Bottom")
		(5 "F.SilkS" user "Ref Des/Silkscreen Top")
		(7 "B.SilkS" user "Ref Des/Silkscreen Bottom")
		(1 "F.Mask" user "Board Geometry/Soldermask Top")
		(3 "B.Mask" user "Board Geometry/Soldermask Bottom")
		(17 "Dwgs.User" user "User.Drawings")
		(19 "Cmts.User" user "User.Comments")
		(21 "Eco1.User" user "User.Eco1")
		(23 "Eco2.User" user "User.Eco2")
		(25 "Edge.Cuts" user "Board Geometry/Outline")
		(27 "Margin" user)
		(31 "F.CrtYd" user "Package Geometry/Place Bound Top")
		(29 "B.CrtYd" user "Package Geometry/Place Bound Bottom")
		(35 "F.Fab" user "Ref Des/Assembly Top")
		(33 "B.Fab" user "Ref Des/Assembly Bottom")
	)
	(footprint ""
		(layer "F.Cu")
		(at 82.706718 -19.142202 -90)
		(property "Reference" "R3825"
			(at 0 0 270)
			(layer "F.SilkS")
			(hide yes)
			(effects
				(font
					(size 1.27 1.27)
				)
			)
		)
		(property "Value" ""
			(at 0 0 270)
			(layer "F.Fab")
			(effects
				(font
					(size 1.27 1.27)
				)
			)
		)
		(duplicate_pad_numbers_are_jumpers no)
		(fp_line
			(start -0.7874 0.4064)
			(end -0.7874 -0.4064)
			(stroke
				(width 0.1524)
				(type default)
			)
			(layer "F.SilkS")
		)
		(fp_line
			(start 0.7874 0.4064)
			(end -0.7874 0.4064)
			(stroke
				(width 0.1524)
				(type default)
			)
			(layer "F.SilkS")
		)
		(fp_line
			(start -0.7874 -0.4064)
			(end 0.7874 -0.4064)
			(stroke
				(width 0.1524)
				(type default)
			)
			(layer "F.SilkS")
		)
		(fp_line
			(start 0.7874 -0.4064)
			(end 0.7874 0.4064)
			(stroke
				(width 0.1524)
				(type default)
			)
			(layer "F.SilkS")
		)
		(fp_line
			(start -0.67945 0.3048)
			(end -0.67945 -0.305054)
			(stroke
				(width 0.1)
				(type default)
			)
			(layer "F.Fab")
		)
		(fp_line
			(start -0.12065 0.3048)
			(end -0.67945 0.3048)
			(stroke
				(width 0.1)
				(type default)
			)
			(layer "F.Fab")
		)
		(fp_line
			(start 0.120396 0.3048)
			(end 0.120396 0.2794)
			(stroke
				(width 0.1)
				(type default)
			)
			(layer "F.Fab")
		)
		(fp_line
			(start 0.67945 0.3048)
			(end 0.120396 0.3048)
			(stroke
				(width 0.1)
				(type default)
			)
			(layer "F.Fab")
		)
		(fp_line
			(start -0.12065 0.2794)
			(end -0.12065 0.3048)
			(stroke
				(width 0.1)
				(type default)
			)
			(layer "F.Fab")
		)
		(fp_line
			(start 0.120396 0.2794)
			(end -0.12065 0.2794)
			(stroke
				(width 0.1)
				(type default)
			)
			(layer "F.Fab")
		)
		(fp_line
			(start -0.12065 -0.2794)
			(end 0.12065 -0.2794)
			(stroke
				(width 0.1)
				(type default)
			)
			(layer "F.Fab")
		)
		(fp_line
			(start 0.12065 -0.2794)
			(end 0.12065 -0.3048)
			(stroke
				(width 0.1)
				(type default)
			)
			(layer "F.Fab")
		)
		(fp_line
			(start 0.12065 -0.3048)
			(end 0.67945 -0.3048)
			(stroke
				(width 0.1)
				(type default)
			)
			(layer "F.Fab")
		)
		(fp_line
			(start 0.67945 -0.3048)
			(end 0.67945 0.3048)
			(stroke
				(width 0.1)
				(type default)
			)
			(layer "F.Fab")
		)
		(fp_line
			(start -0.67945 -0.305054)
			(end -0.12065 -0.305054)
			(stroke
				(width 0.1)
				(type default)
			)
			(layer "F.Fab")
		)
		(fp_line
			(start -0.12065 -0.305054)
			(end -0.12065 -0.2794)
			(stroke
				(width 0.1)
				(type default)
			)
			(layer "F.Fab")
		)
		(pad "1" smd circle
			(at -0.40005 0 270)
			(size 0 0)
			(layers "F.Cu" "F.Mask" "F.Paste")
			(net "P3V3_AUX")
		)
		(pad "2" smd circle
			(at 0.40005 0 270)
			(size 0 0)
			(layers "F.Cu" "F.Mask" "F.Paste")
			(net "HP_LVC3_OCP_V3_2_P12V_PWRGD")
		)
	)
	(footprint ""
		(layer "F.Cu")
		(at 118.44528 -405.823166 -90)
		(property "Reference" "R2831"
			(at 0 0 270)
			(layer "F.SilkS")
			(hide yes)
			(effects
				(font
					(size 1.27 1.27)
				)
			)
		)
		(property "Value" ""
			(at 0 0 270)
			(layer "F.Fab")
			(effects
				(font
					(size 1.27 1.27)
				)
			)
		)
		(duplicate_pad_numbers_are_jumpers no)
		(fp_line
			(start -0.7874 0.4064)
			(end -0.7874 -0.4064)
			(stroke
				(width 0.1524)
				(type default)
			)
			(layer "F.SilkS")
		)
		(fp_line
			(start 0.7874 0.4064)
			(end -0.7874 0.4064)
			(stroke
				(width 0.1524)
				(type default)
			)
			(layer "F.SilkS")
		)
		(fp_line
			(start -0.7874 -0.4064)
			(end 0.7874 -0.4064)
			(stroke
				(width 0.1524)
				(type default)
			)
			(layer "F.SilkS")
		)
		(fp_line
			(start 0.7874 -0.4064)
			(end 0.7874 0.4064)
			(stroke
				(width 0.1524)
				(type default)
			)
			(layer "F.SilkS")
		)
		(fp_line
			(start -0.67945 0.3048)
			(end -0.67945 -0.305054)
			(stroke
				(width 0.1)
				(type default)
			)
			(layer "F.Fab")
		)
		(fp_line
			(start -0.12065 0.3048)
			(end -0.67945 0.3048)
			(stroke
				(width 0.1)
				(type default)
			)
			(layer "F.Fab")
		)
		(fp_line
			(start 0.120396 0.3048)
			(end 0.120396 0.2794)
			(stroke
				(width 0.1)
				(type default)
			)
			(layer "F.Fab")
		)
		(fp_line
			(start 0.67945 0.3048)
			(end 0.120396 0.3048)
			(stroke
				(width 0.1)
				(type default)
			)
			(layer "F.Fab")
		)
		(fp_line
			(start -0.12065 0.2794)
			(end -0.12065 0.3048)
			(stroke
				(width 0.1)
				(type default)
			)
			(layer "F.Fab")
		)
		(fp_line
			(start 0.120396 0.2794)
			(end -0.12065 0.2794)
			(stroke
				(width 0.1)
				(type default)
			)
			(layer "F.Fab")
		)
		(fp_line
			(start -0.12065 -0.2794)
			(end 0.12065 -0.2794)
			(stroke
				(width 0.1)
				(type default)
			)
			(layer "F.Fab")
		)
		(fp_line
			(start 0.12065 -0.2794)
			(end 0.12065 -0.3048)
			(stroke
				(width 0.1)
				(type default)
			)
			(layer "F.Fab")
		)
		(fp_line
			(start 0.12065 -0.3048)
			(end 0.67945 -0.3048)
			(stroke
				(width 0.1)
				(type default)
			)
			(layer "F.Fab")
		)
		(fp_line
			(start 0.67945 -0.3048)
			(end 0.67945 0.3048)
			(stroke
				(width 0.1)
				(type default)
			)
			(layer "F.Fab")
		)
		(fp_line
			(start -0.67945 -0.305054)
			(end -0.12065 -0.305054)
			(stroke
				(width 0.1)
				(type default)
			)
			(layer "F.Fab")
		)
		(fp_line
			(start -0.12065 -0.305054)
			(end -0.12065 -0.2794)
			(stroke
				(width 0.1)
				(type default)
			)
			(layer "F.Fab")
		)
		(pad "1" smd circle
			(at -0.40005 0 270)
			(size 0 0)
			(layers "F.Cu" "F.Mask" "F.Paste")
			(net "BIC_MONITER")
		)
		(pad "2" smd circle
			(at 0.40005 0 270)
			(size 0 0)
			(layers "F.Cu" "F.Mask" "F.Paste")
			(net "GND")
		)
	)
)
